(kicad_pcb
	(version 20260206)
	(generator "pcbnew")
	(generator_version "10.0")
	(general
		(thickness 1.6)
		(legacy_teardrops no)
	)
	(paper "A4")
	(title_block
		(title "03242023_DA0F0TMBIJ0_F0T_Motherboard_J_brd_V01_OCP.brd")
		(comment 1 "Grand Teton / footprints 2590-2590 of 6105")
	)
	(layers
		(0 "F.Cu" signal "TOP")
		(4 "In1.Cu" signal "GND")
		(6 "In2.Cu" signal "IN1")
		(8 "In3.Cu" signal "GND1")
		(10 "In4.Cu" signal "IN2")
		(12 "In5.Cu" signal "GND2")
		(14 "In6.Cu" signal "IN3")
		(16 "In7.Cu" signal "GND3")
		(18 "In8.Cu" signal "VCC")
		(20 "In9.Cu" signal "VCC1")
		(22 "In10.Cu" signal "GND4")
		(24 "In11.Cu" signal "IN4")
		(26 "In12.Cu" signal "GND5")
		(28 "In13.Cu" signal "IN5")
		(30 "In14.Cu" signal "GND6")
		(32 "In15.Cu" signal "IN6")
		(34 "In16.Cu" signal "GND7")
		(2 "B.Cu" signal "BOTTOM")
		(9 "F.Adhes" user "F.Adhesive")
		(11 "B.Adhes" user "B.Adhesive")
		(13 "F.Paste" user "Package Geometry/Pastemask Top")
		(15 "B.Paste" user "Package Geometry/Pastemask Bottom")
		(5 "F.SilkS" user "Ref Des/Silkscreen Top")
		(7 "B.SilkS" user "Ref Des/Silkscreen Bottom")
		(1 "F.Mask" user "Board Geometry/Soldermask Top")
		(3 "B.Mask" user "Board Geometry/Soldermask Bottom")
		(17 "Dwgs.User" user "User.Drawings")
		(19 "Cmts.User" user "User.Comments")
		(21 "Eco1.User" user "User.Eco1")
		(23 "Eco2.User" user "User.Eco2")
		(25 "Edge.Cuts" user "Board Geometry/Outline")
		(27 "Margin" user)
		(31 "F.CrtYd" user "Package Geometry/Place Bound Top")
		(29 "B.CrtYd" user "Package Geometry/Place Bound Bottom")
		(35 "F.Fab" user "Ref Des/Assembly Top")
		(33 "B.Fab" user "Ref Des/Assembly Bottom")
	)
	(footprint ""
		(layer "F.Cu")
		(at 186.23788 -97.119948 -90)
		(property "Reference" "R168"
			(at 0 0 270)
			(layer "F.SilkS")
			(hide yes)
			(effects
				(font
					(size 1.27 1.27)
				)
			)
		)
		(property "Value" ""
			(at 0 0 270)
			(layer "F.Fab")
			(effects
				(font
					(size 1.27 1.27)
				)
			)
		)
		(duplicate_pad_numbers_are_jumpers no)
		(fp_line
			(start -0.7874 0.4064)
			(end -0.7874 -0.4064)
			(stroke
				(width 0.1524)
				(type default)
			)
			(layer "F.SilkS")
		)
		(fp_line
			(start 0.7874 0.4064)
			(end -0.7874 0.4064)
			(stroke
				(width 0.1524)
				(type default)
			)
			(layer "F.SilkS")
		)
		(fp_line
			(start -0.7874 -0.4064)
			(end 0.7874 -0.4064)
			(stroke
				(width 0.1524)
				(type default)
			)
			(layer "F.SilkS")
		)
		(fp_line
			(start 0.7874 -0.4064)
			(end 0.7874 0.4064)
			(stroke
				(width 0.1524)
				(type default)
			)
			(layer "F.SilkS")
		)
		(fp_line
			(start -0.67945 0.3048)
			(end -0.67945 -0.305054)
			(stroke
				(width 0.1)
				(type default)
			)
			(layer "F.Fab")
		)
		(fp_line
			(start -0.12065 0.3048)
			(end -0.67945 0.3048)
			(stroke
				(width 0.1)
				(type default)
			)
			(layer "F.Fab")
		)
		(fp_line
			(start 0.120396 0.3048)
			(end 0.120396 0.2794)
			(stroke
				(width 0.1)
				(type default)
			)
			(layer "F.Fab")
		)
		(fp_line
			(start 0.67945 0.3048)
			(end 0.120396 0.3048)
			(stroke
				(width 0.1)
				(type default)
			)
			(layer "F.Fab")
		)
		(fp_line
			(start -0.12065 0.2794)
			(end -0.12065 0.3048)
			(stroke
				(width 0.1)
				(type default)
			)
			(layer "F.Fab")
		)
		(fp_line
			(start 0.120396 0.2794)
			(end -0.12065 0.2794)
			(stroke
				(width 0.1)
				(type default)
			)
			(layer "F.Fab")
		)
		(fp_line
			(start -0.12065 -0.2794)
			(end 0.12065 -0.2794)
			(stroke
				(width 0.1)
				(type default)
			)
			(layer "F.Fab")
		)
		(fp_line
			(start 0.12065 -0.2794)
			(end 0.12065 -0.3048)
			(stroke
				(width 0.1)
				(type default)
			)
			(layer "F.Fab")
		)
		(fp_line
			(start 0.12065 -0.3048)
			(end 0.67945 -0.3048)
			(stroke
				(width 0.1)
				(type default)
			)
			(layer "F.Fab")
		)
		(fp_line
			(start 0.67945 -0.3048)
			(end 0.67945 0.3048)
			(stroke
				(width 0.1)
				(type default)
			)
			(layer "F.Fab")
		)
		(fp_line
			(start -0.67945 -0.305054)
			(end -0.12065 -0.305054)
			(stroke
				(width 0.1)
				(type default)
			)
			(layer "F.Fab")
		)
		(fp_line
			(start -0.12065 -0.305054)
			(end -0.12065 -0.2794)
			(stroke
				(width 0.1)
				(type default)
			)
			(layer "F.Fab")
		)
		(pad "1" smd circle
			(at -0.40005 0 270)
			(size 0 0)
			(layers "F.Cu" "F.Mask" "F.Paste")
			(net "PWRGD_CPU0_LVC1_R")
		)
		(pad "2" smd circle
			(at 0.40005 0 270)
			(size 0 0)
			(layers "F.Cu" "F.Mask" "F.Paste")
			(net "PWRGD_CPU0_BUF_R")
		)
	)
)
